(kicad_pcb
	(version 20260206)
	(generator "pcbnew")
	(generator_version "10.0")
	(general
		(thickness 1.6)
		(legacy_teardrops no)
	)
	(paper "A4")
	(title_block
		(title "03242023_DA0F0TMBIJ0_F0T_Motherboard_J_brd_V01_OCP.brd")
		(comment 1 "Grand Teton / footprints 1014-1019 of 6105")
	)
	(layers
		(0 "F.Cu" signal "TOP")
		(4 "In1.Cu" signal "GND")
		(6 "In2.Cu" signal "IN1")
		(8 "In3.Cu" signal "GND1")
		(10 "In4.Cu" signal "IN2")
		(12 "In5.Cu" signal "GND2")
		(14 "In6.Cu" signal "IN3")
		(16 "In7.Cu" signal "GND3")
		(18 "In8.Cu" signal "VCC")
		(20 "In9.Cu" signal "VCC1")
		(22 "In10.Cu" signal "GND4")
		(24 "In11.Cu" signal "IN4")
		(26 "In12.Cu" signal "GND5")
		(28 "In13.Cu" signal "IN5")
		(30 "In14.Cu" signal "GND6")
		(32 "In15.Cu" signal "IN6")
		(34 "In16.Cu" signal "GND7")
		(2 "B.Cu" signal "BOTTOM")
		(9 "F.Adhes" user "F.Adhesive")
		(11 "B.Adhes" user "B.Adhesive")
		(13 "F.Paste" user "Package Geometry/Pastemask Top")
		(15 "B.Paste" user "Package Geometry/Pastemask Bottom")
		(5 "F.SilkS" user "Ref Des/Silkscreen Top")
		(7 "B.SilkS" user "Ref Des/Silkscreen Bottom")
		(1 "F.Mask" user "Board Geometry/Soldermask Top")
		(3 "B.Mask" user "Board Geometry/Soldermask Bottom")
		(17 "Dwgs.User" user "User.Drawings")
		(19 "Cmts.User" user "User.Comments")
		(21 "Eco1.User" user "User.Eco1")
		(23 "Eco2.User" user "User.Eco2")
		(25 "Edge.Cuts" user "Board Geometry/Outline")
		(27 "Margin" user)
		(31 "F.CrtYd" user "Package Geometry/Place Bound Top")
		(29 "B.CrtYd" user "Package Geometry/Place Bound Bottom")
		(35 "F.Fab" user "Ref Des/Assembly Top")
		(33 "B.Fab" user "Ref Des/Assembly Bottom")
	)
	(footprint ""
		(layer "F.Cu")
		(at 96.48444 -65.143634 -90)
		(property "Reference" "R3098"
			(at 0 0 270)
			(layer "F.SilkS")
			(hide yes)
			(effects
				(font
					(size 1.27 1.27)
				)
			)
		)
		(property "Value" ""
			(at 0 0 270)
			(layer "F.Fab")
			(effects
				(font
					(size 1.27 1.27)
				)
			)
		)
		(duplicate_pad_numbers_are_jumpers no)
		(fp_line
			(start -0.7874 0.4064)
			(end -0.7874 -0.4064)
			(stroke
				(width 0.1524)
				(type default)
			)
			(layer "F.SilkS")
		)
		(fp_line
			(start 0.7874 0.4064)
			(end -0.7874 0.4064)
			(stroke
				(width 0.1524)
				(type default)
			)
			(layer "F.SilkS")
		)
		(fp_line
			(start -0.7874 -0.4064)
			(end 0.7874 -0.4064)
			(stroke
				(width 0.1524)
				(type default)
			)
			(layer "F.SilkS")
		)
		(fp_line
			(start 0.7874 -0.4064)
			(end 0.7874 0.4064)
			(stroke
				(width 0.1524)
				(type default)
			)
			(layer "F.SilkS")
		)
		(fp_line
			(start -0.67945 0.3048)
			(end -0.67945 -0.305054)
			(stroke
				(width 0.1)
				(type default)
			)
			(layer "F.Fab")
		)
		(fp_line
			(start -0.12065 0.3048)
			(end -0.67945 0.3048)
			(stroke
				(width 0.1)
				(type default)
			)
			(layer "F.Fab")
		)
		(fp_line
			(start 0.120396 0.3048)
			(end 0.120396 0.2794)
			(stroke
				(width 0.1)
				(type default)
			)
			(layer "F.Fab")
		)
		(fp_line
			(start 0.67945 0.3048)
			(end 0.120396 0.3048)
			(stroke
				(width 0.1)
				(type default)
			)
			(layer "F.Fab")
		)
		(fp_line
			(start -0.12065 0.2794)
			(end -0.12065 0.3048)
			(stroke
				(width 0.1)
				(type default)
			)
			(layer "F.Fab")
		)
		(fp_line
			(start 0.120396 0.2794)
			(end -0.12065 0.2794)
			(stroke
				(width 0.1)
				(type default)
			)
			(layer "F.Fab")
		)
		(fp_line
			(start -0.12065 -0.2794)
			(end 0.12065 -0.2794)
			(stroke
				(width 0.1)
				(type default)
			)
			(layer "F.Fab")
		)
		(fp_line
			(start 0.12065 -0.2794)
			(end 0.12065 -0.3048)
			(stroke
				(width 0.1)
				(type default)
			)
			(layer "F.Fab")
		)
		(fp_line
			(start 0.12065 -0.3048)
			(end 0.67945 -0.3048)
			(stroke
				(width 0.1)
				(type default)
			)
			(layer "F.Fab")
		)
		(fp_line
			(start 0.67945 -0.3048)
			(end 0.67945 0.3048)
			(stroke
				(width 0.1)
				(type default)
			)
			(layer "F.Fab")
		)
		(fp_line
			(start -0.67945 -0.305054)
			(end -0.12065 -0.305054)
			(stroke
				(width 0.1)
				(type default)
			)
			(layer "F.Fab")
		)
		(fp_line
			(start -0.12065 -0.305054)
			(end -0.12065 -0.2794)
			(stroke
				(width 0.1)
				(type default)
			)
			(layer "F.Fab")
		)
		(pad "1" smd circle
			(at -0.40005 0 270)
			(size 0 0)
			(layers "F.Cu" "F.Mask" "F.Paste")
			(net "LED_PWRGD_PVCCIN_CPU1")
		)
		(pad "2" smd circle
			(at 0.40005 0 270)
			(size 0 0)
			(layers "F.Cu" "F.Mask" "F.Paste")
			(net "P3V3_AUX")
		)
	)
	(footprint ""
		(layer "F.Cu")
		(at 24.7015 -182.59552)
		(property "Reference" "PR2220"
			(at 0 0 0)
			(layer "F.SilkS")
			(hide yes)
			(effects
				(font
					(size 1.27 1.27)
				)
			)
		)
		(property "Value" ""
			(at 0 0 0)
			(layer "F.Fab")
			(effects
				(font
					(size 1.27 1.27)
				)
			)
		)
		(duplicate_pad_numbers_are_jumpers no)
		(fp_line
			(start -0.7874 -0.4064)
			(end 0.7874 -0.4064)
			(stroke
				(width 0.1524)
				(type default)
			)
			(layer "F.SilkS")
		)
		(fp_line
			(start -0.7874 0.4064)
			(end -0.7874 -0.4064)
			(stroke
				(width 0.1524)
				(type default)
			)
			(layer "F.SilkS")
		)
		(fp_line
			(start 0.7874 -0.4064)
			(end 0.7874 0.4064)
			(stroke
				(width 0.1524)
				(type default)
			)
			(layer "F.SilkS")
		)
		(fp_line
			(start 0.7874 0.4064)
			(end -0.7874 0.4064)
			(stroke
				(width 0.1524)
				(type default)
			)
			(layer "F.SilkS")
		)
		(fp_line
			(start -0.67945 -0.305054)
			(end -0.12065 -0.305054)
			(stroke
				(width 0.1)
				(type default)
			)
			(layer "F.Fab")
		)
		(fp_line
			(start -0.67945 0.3048)
			(end -0.67945 -0.305054)
			(stroke
				(width 0.1)
				(type default)
			)
			(layer "F.Fab")
		)
		(fp_line
			(start -0.12065 -0.305054)
			(end -0.12065 -0.2794)
			(stroke
				(width 0.1)
				(type default)
			)
			(layer "F.Fab")
		)
		(fp_line
			(start -0.12065 -0.2794)
			(end 0.12065 -0.2794)
			(stroke
				(width 0.1)
				(type default)
			)
			(layer "F.Fab")
		)
		(fp_line
			(start -0.12065 0.2794)
			(end -0.12065 0.3048)
			(stroke
				(width 0.1)
				(type default)
			)
			(layer "F.Fab")
		)
		(fp_line
			(start -0.12065 0.3048)
			(end -0.67945 0.3048)
			(stroke
				(width 0.1)
				(type default)
			)
			(layer "F.Fab")
		)
		(fp_line
			(start 0.120396 0.2794)
			(end -0.12065 0.2794)
			(stroke
				(width 0.1)
				(type default)
			)
			(layer "F.Fab")
		)
		(fp_line
			(start 0.120396 0.3048)
			(end 0.120396 0.2794)
			(stroke
				(width 0.1)
				(type default)
			)
			(layer "F.Fab")
		)
		(fp_line
			(start 0.12065 -0.3048)
			(end 0.67945 -0.3048)
			(stroke
				(width 0.1)
				(type default)
			)
			(layer "F.Fab")
		)
		(fp_line
			(start 0.12065 -0.2794)
			(end 0.12065 -0.3048)
			(stroke
				(width 0.1)
				(type default)
			)
			(layer "F.Fab")
		)
		(fp_line
			(start 0.67945 -0.3048)
			(end 0.67945 0.3048)
			(stroke
				(width 0.1)
				(type default)
			)
			(layer "F.Fab")
		)
		(fp_line
			(start 0.67945 0.3048)
			(end 0.120396 0.3048)
			(stroke
				(width 0.1)
				(type default)
			)
			(layer "F.Fab")
		)
		(pad "1" smd circle
			(at -0.40005 0)
			(size 0 0)
			(layers "F.Cu" "F.Mask" "F.Paste")
			(net "PVNN_MAIN_CPU1_MODE")
		)
		(pad "2" smd circle
			(at 0.40005 0)
			(size 0 0)
			(layers "F.Cu" "F.Mask" "F.Paste")
			(net "GND")
		)
	)
	(footprint ""
		(layer "F.Cu")
		(at 420.473632 -161.490914)
		(property "Reference" "PR1784"
			(at 0 0 0)
			(layer "F.SilkS")
			(hide yes)
			(effects
				(font
					(size 1.27 1.27)
				)
			)
		)
		(property "Value" ""
			(at 0 0 0)
			(layer "F.Fab")
			(effects
				(font
					(size 1.27 1.27)
				)
			)
		)
		(duplicate_pad_numbers_are_jumpers no)
		(fp_line
			(start -0.7874 -0.4064)
			(end 0.7874 -0.4064)
			(stroke
				(width 0.1524)
				(type default)
			)
			(layer "F.SilkS")
		)
		(fp_line
			(start -0.7874 0.4064)
			(end -0.7874 -0.4064)
			(stroke
				(width 0.1524)
				(type default)
			)
			(layer "F.SilkS")
		)
		(fp_line
			(start 0.7874 -0.4064)
			(end 0.7874 0.4064)
			(stroke
				(width 0.1524)
				(type default)
			)
			(layer "F.SilkS")
		)
		(fp_line
			(start 0.7874 0.4064)
			(end -0.7874 0.4064)
			(stroke
				(width 0.1524)
				(type default)
			)
			(layer "F.SilkS")
		)
		(fp_line
			(start -0.67945 -0.305054)
			(end -0.12065 -0.305054)
			(stroke
				(width 0.1)
				(type default)
			)
			(layer "F.Fab")
		)
		(fp_line
			(start -0.67945 0.3048)
			(end -0.67945 -0.305054)
			(stroke
				(width 0.1)
				(type default)
			)
			(layer "F.Fab")
		)
		(fp_line
			(start -0.12065 -0.305054)
			(end -0.12065 -0.2794)
			(stroke
				(width 0.1)
				(type default)
			)
			(layer "F.Fab")
		)
		(fp_line
			(start -0.12065 -0.2794)
			(end 0.12065 -0.2794)
			(stroke
				(width 0.1)
				(type default)
			)
			(layer "F.Fab")
		)
		(fp_line
			(start -0.12065 0.2794)
			(end -0.12065 0.3048)
			(stroke
				(width 0.1)
				(type default)
			)
			(layer "F.Fab")
		)
		(fp_line
			(start -0.12065 0.3048)
			(end -0.67945 0.3048)
			(stroke
				(width 0.1)
				(type default)
			)
			(layer "F.Fab")
		)
		(fp_line
			(start 0.120396 0.2794)
			(end -0.12065 0.2794)
			(stroke
				(width 0.1)
				(type default)
			)
			(layer "F.Fab")
		)
		(fp_line
			(start 0.120396 0.3048)
			(end 0.120396 0.2794)
			(stroke
				(width 0.1)
				(type default)
			)
			(layer "F.Fab")
		)
		(fp_line
			(start 0.12065 -0.3048)
			(end 0.67945 -0.3048)
			(stroke
				(width 0.1)
				(type default)
			)
			(layer "F.Fab")
		)
		(fp_line
			(start 0.12065 -0.2794)
			(end 0.12065 -0.3048)
			(stroke
				(width 0.1)
				(type default)
			)
			(layer "F.Fab")
		)
		(fp_line
			(start 0.67945 -0.3048)
			(end 0.67945 0.3048)
			(stroke
				(width 0.1)
				(type default)
			)
			(layer "F.Fab")
		)
		(fp_line
			(start 0.67945 0.3048)
			(end 0.120396 0.3048)
			(stroke
				(width 0.1)
				(type default)
			)
			(layer "F.Fab")
		)
		(pad "1" smd circle
			(at -0.40005 0)
			(size 0 0)
			(layers "F.Cu" "F.Mask" "F.Paste")
			(net "SW_PVCCD_HV_CPU0_BOOT1")
		)
		(pad "2" smd circle
			(at 0.40005 0)
			(size 0 0)
			(layers "F.Cu" "F.Mask" "F.Paste")
			(net "SW_PVCCD_HV_CPU0_BOOT1_R")
		)
	)
	(footprint ""
		(layer "F.Cu")
		(at 376.2883 -342.270334)
		(property "Reference" "PR139"
			(at 0 0 0)
			(layer "F.SilkS")
			(hide yes)
			(effects
				(font
					(size 1.27 1.27)
				)
			)
		)
		(property "Value" ""
			(at 0 0 0)
			(layer "F.Fab")
			(effects
				(font
					(size 1.27 1.27)
				)
			)
		)
		(duplicate_pad_numbers_are_jumpers no)
		(fp_line
			(start -0.7874 -0.4064)
			(end 0.7874 -0.4064)
			(stroke
				(width 0.1524)
				(type default)
			)
			(layer "F.SilkS")
		)
		(fp_line
			(start -0.7874 0.4064)
			(end -0.7874 -0.4064)
			(stroke
				(width 0.1524)
				(type default)
			)
			(layer "F.SilkS")
		)
		(fp_line
			(start 0.7874 -0.4064)
			(end 0.7874 0.4064)
			(stroke
				(width 0.1524)
				(type default)
			)
			(layer "F.SilkS")
		)
		(fp_line
			(start 0.7874 0.4064)
			(end -0.7874 0.4064)
			(stroke
				(width 0.1524)
				(type default)
			)
			(layer "F.SilkS")
		)
		(fp_line
			(start -0.67945 -0.305054)
			(end -0.12065 -0.305054)
			(stroke
				(width 0.1)
				(type default)
			)
			(layer "F.Fab")
		)
		(fp_line
			(start -0.67945 0.3048)
			(end -0.67945 -0.305054)
			(stroke
				(width 0.1)
				(type default)
			)
			(layer "F.Fab")
		)
		(fp_line
			(start -0.12065 -0.305054)
			(end -0.12065 -0.2794)
			(stroke
				(width 0.1)
				(type default)
			)
			(layer "F.Fab")
		)
		(fp_line
			(start -0.12065 -0.2794)
			(end 0.12065 -0.2794)
			(stroke
				(width 0.1)
				(type default)
			)
			(layer "F.Fab")
		)
		(fp_line
			(start -0.12065 0.2794)
			(end -0.12065 0.3048)
			(stroke
				(width 0.1)
				(type default)
			)
			(layer "F.Fab")
		)
		(fp_line
			(start -0.12065 0.3048)
			(end -0.67945 0.3048)
			(stroke
				(width 0.1)
				(type default)
			)
			(layer "F.Fab")
		)
		(fp_line
			(start 0.120396 0.2794)
			(end -0.12065 0.2794)
			(stroke
				(width 0.1)
				(type default)
			)
			(layer "F.Fab")
		)
		(fp_line
			(start 0.120396 0.3048)
			(end 0.120396 0.2794)
			(stroke
				(width 0.1)
				(type default)
			)
			(layer "F.Fab")
		)
		(fp_line
			(start 0.12065 -0.3048)
			(end 0.67945 -0.3048)
			(stroke
				(width 0.1)
				(type default)
			)
			(layer "F.Fab")
		)
		(fp_line
			(start 0.12065 -0.2794)
			(end 0.12065 -0.3048)
			(stroke
				(width 0.1)
				(type default)
			)
			(layer "F.Fab")
		)
		(fp_line
			(start 0.67945 -0.3048)
			(end 0.67945 0.3048)
			(stroke
				(width 0.1)
				(type default)
			)
			(layer "F.Fab")
		)
		(fp_line
			(start 0.67945 0.3048)
			(end 0.120396 0.3048)
			(stroke
				(width 0.1)
				(type default)
			)
			(layer "F.Fab")
		)
		(pad "1" smd circle
			(at -0.40005 0)
			(size 0 0)
			(layers "F.Cu" "F.Mask" "F.Paste")
			(net "PVCCIN_CPU0_LSET5")
		)
		(pad "2" smd circle
			(at 0.40005 0)
			(size 0 0)
			(layers "F.Cu" "F.Mask" "F.Paste")
			(net "GND")
		)
	)
	(footprint ""
		(layer "F.Cu")
		(at 75.738736 -74.901552 -90)
		(property "Reference" "R3089"
			(at 0 0 270)
			(layer "F.SilkS")
			(hide yes)
			(effects
				(font
					(size 1.27 1.27)
				)
			)
		)
		(property "Value" ""
			(at 0 0 270)
			(layer "F.Fab")
			(effects
				(font
					(size 1.27 1.27)
				)
			)
		)
		(duplicate_pad_numbers_are_jumpers no)
		(fp_line
			(start -0.7874 0.4064)
			(end -0.7874 -0.4064)
			(stroke
				(width 0.1524)
				(type default)
			)
			(layer "F.SilkS")
		)
		(fp_line
			(start 0.7874 0.4064)
			(end -0.7874 0.4064)
			(stroke
				(width 0.1524)
				(type default)
			)
			(layer "F.SilkS")
		)
		(fp_line
			(start -0.7874 -0.4064)
			(end 0.7874 -0.4064)
			(stroke
				(width 0.1524)
				(type default)
			)
			(layer "F.SilkS")
		)
		(fp_line
			(start 0.7874 -0.4064)
			(end 0.7874 0.4064)
			(stroke
				(width 0.1524)
				(type default)
			)
			(layer "F.SilkS")
		)
		(fp_line
			(start -0.67945 0.3048)
			(end -0.67945 -0.305054)
			(stroke
				(width 0.1)
				(type default)
			)
			(layer "F.Fab")
		)
		(fp_line
			(start -0.12065 0.3048)
			(end -0.67945 0.3048)
			(stroke
				(width 0.1)
				(type default)
			)
			(layer "F.Fab")
		)
		(fp_line
			(start 0.120396 0.3048)
			(end 0.120396 0.2794)
			(stroke
				(width 0.1)
				(type default)
			)
			(layer "F.Fab")
		)
		(fp_line
			(start 0.67945 0.3048)
			(end 0.120396 0.3048)
			(stroke
				(width 0.1)
				(type default)
			)
			(layer "F.Fab")
		)
		(fp_line
			(start -0.12065 0.2794)
			(end -0.12065 0.3048)
			(stroke
				(width 0.1)
				(type default)
			)
			(layer "F.Fab")
		)
		(fp_line
			(start 0.120396 0.2794)
			(end -0.12065 0.2794)
			(stroke
				(width 0.1)
				(type default)
			)
			(layer "F.Fab")
		)
		(fp_line
			(start -0.12065 -0.2794)
			(end 0.12065 -0.2794)
			(stroke
				(width 0.1)
				(type default)
			)
			(layer "F.Fab")
		)
		(fp_line
			(start 0.12065 -0.2794)
			(end 0.12065 -0.3048)
			(stroke
				(width 0.1)
				(type default)
			)
			(layer "F.Fab")
		)
		(fp_line
			(start 0.12065 -0.3048)
			(end 0.67945 -0.3048)
			(stroke
				(width 0.1)
				(type default)
			)
			(layer "F.Fab")
		)
		(fp_line
			(start 0.67945 -0.3048)
			(end 0.67945 0.3048)
			(stroke
				(width 0.1)
				(type default)
			)
			(layer "F.Fab")
		)
		(fp_line
			(start -0.67945 -0.305054)
			(end -0.12065 -0.305054)
			(stroke
				(width 0.1)
				(type default)
			)
			(layer "F.Fab")
		)
		(fp_line
			(start -0.12065 -0.305054)
			(end -0.12065 -0.2794)
			(stroke
				(width 0.1)
				(type default)
			)
			(layer "F.Fab")
		)
		(pad "1" smd circle
			(at -0.40005 0 270)
			(size 0 0)
			(layers "F.Cu" "F.Mask" "F.Paste")
			(net "LED_PWRGD_PVCCFA_EHV_CPU0")
		)
		(pad "2" smd circle
			(at 0.40005 0 270)
			(size 0 0)
			(layers "F.Cu" "F.Mask" "F.Paste")
			(net "P3V3_AUX")
		)
	)
	(footprint ""
		(layer "F.Cu")
		(at 360.444542 -390.43737)
		(property "Reference" "R4162"
			(at 0 0 0)
			(layer "F.SilkS")
			(hide yes)
			(effects
				(font
					(size 1.27 1.27)
				)
			)
		)
		(property "Value" ""
			(at 0 0 0)
			(layer "F.Fab")
			(effects
				(font
					(size 1.27 1.27)
				)
			)
		)
		(duplicate_pad_numbers_are_jumpers no)
		(fp_line
			(start -0.7874 -0.4064)
			(end 0.7874 -0.4064)
			(stroke
				(width 0.1524)
				(type default)
			)
			(layer "F.SilkS")
		)
		(fp_line
			(start -0.7874 0.4064)
			(end -0.7874 -0.4064)
			(stroke
				(width 0.1524)
				(type default)
			)
			(layer "F.SilkS")
		)
		(fp_line
			(start 0.7874 -0.4064)
			(end 0.7874 0.4064)
			(stroke
				(width 0.1524)
				(type default)
			)
			(layer "F.SilkS")
		)
		(fp_line
			(start 0.7874 0.4064)
			(end -0.7874 0.4064)
			(stroke
				(width 0.1524)
				(type default)
			)
			(layer "F.SilkS")
		)
		(fp_line
			(start -0.67945 -0.305054)
			(end -0.12065 -0.305054)
			(stroke
				(width 0.1)
				(type default)
			)
			(layer "F.Fab")
		)
		(fp_line
			(start -0.67945 0.3048)
			(end -0.67945 -0.305054)
			(stroke
				(width 0.1)
				(type default)
			)
			(layer "F.Fab")
		)
		(fp_line
			(start -0.12065 -0.305054)
			(end -0.12065 -0.2794)
			(stroke
				(width 0.1)
				(type default)
			)
			(layer "F.Fab")
		)
		(fp_line
			(start -0.12065 -0.2794)
			(end 0.12065 -0.2794)
			(stroke
				(width 0.1)
				(type default)
			)
			(layer "F.Fab")
		)
		(fp_line
			(start -0.12065 0.2794)
			(end -0.12065 0.3048)
			(stroke
				(width 0.1)
				(type default)
			)
			(layer "F.Fab")
		)
		(fp_line
			(start -0.12065 0.3048)
			(end -0.67945 0.3048)
			(stroke
				(width 0.1)
				(type default)
			)
			(layer "F.Fab")
		)
		(fp_line
			(start 0.120396 0.2794)
			(end -0.12065 0.2794)
			(stroke
				(width 0.1)
				(type default)
			)
			(layer "F.Fab")
		)
		(fp_line
			(start 0.120396 0.3048)
			(end 0.120396 0.2794)
			(stroke
				(width 0.1)
				(type default)
			)
			(layer "F.Fab")
		)
		(fp_line
			(start 0.12065 -0.3048)
			(end 0.67945 -0.3048)
			(stroke
				(width 0.1)
				(type default)
			)
			(layer "F.Fab")
		)
		(fp_line
			(start 0.12065 -0.2794)
			(end 0.12065 -0.3048)
			(stroke
				(width 0.1)
				(type default)
			)
			(layer "F.Fab")
		)
		(fp_line
			(start 0.67945 -0.3048)
			(end 0.67945 0.3048)
			(stroke
				(width 0.1)
				(type default)
			)
			(layer "F.Fab")
		)
		(fp_line
			(start 0.67945 0.3048)
			(end 0.120396 0.3048)
			(stroke
				(width 0.1)
				(type default)
			)
			(layer "F.Fab")
		)
		(pad "1" smd circle
			(at -0.40005 0)
			(size 0 0)
			(layers "F.Cu" "F.Mask" "F.Paste")
			(net "P3V3_AUX")
		)
		(pad "2" smd circle
			(at 0.40005 0)
			(size 0 0)
			(layers "F.Cu" "F.Mask" "F.Paste")
			(net "GPU_3V3IO_RSVD3")
		)
	)
)
